(kicad_pcb
	(version 20260206)
	(generator "pcbnew")
	(generator_version "10.0")
	(general
		(thickness 1.6)
		(legacy_teardrops no)
	)
	(paper "A4")
	(title_block
		(title "Wiwynn_Tioga_Pass_MB.brd")
		(comment 1 "Tioga Pass / footprint 2254 of 4770 (U5D1), pads 2914-2979 of 3647")
	)
	(layers
		(0 "F.Cu" signal "TOP")
		(4 "In1.Cu" signal "L2GND")
		(6 "In2.Cu" signal "L3")
		(8 "In3.Cu" signal "L4GND")
		(10 "In4.Cu" signal "L5")
		(12 "In5.Cu" signal "L6GND")
		(14 "In6.Cu" signal "L7VCC")
		(16 "In7.Cu" signal "L8VCC")
		(18 "In8.Cu" signal "L9GND")
		(20 "In9.Cu" signal "L10")
		(22 "In10.Cu" signal "L11GND")
		(24 "In11.Cu" signal "L12")
		(26 "In12.Cu" signal "L13GND")
		(2 "B.Cu" signal "BOTTOM")
		(9 "F.Adhes" user "F.Adhesive")
		(11 "B.Adhes" user "B.Adhesive")
		(13 "F.Paste" user "Package Geometry/Pastemask Top")
		(15 "B.Paste" user "Package Geometry/Pastemask Bottom")
		(5 "F.SilkS" user "Ref Des/Silkscreen Top")
		(7 "B.SilkS" user "Ref Des/Silkscreen Bottom")
		(1 "F.Mask" user "Board Geometry/Soldermask Top")
		(3 "B.Mask" user "Board Geometry/Soldermask Bottom")
		(17 "Dwgs.User" user "User.Drawings")
		(19 "Cmts.User" user "User.Comments")
		(21 "Eco1.User" user "User.Eco1")
		(23 "Eco2.User" user "User.Eco2")
		(25 "Edge.Cuts" user "Board Geometry/Outline")
		(27 "Margin" user)
		(31 "F.CrtYd" user "Package Geometry/Place Bound Top")
		(29 "B.CrtYd" user "Package Geometry/Place Bound Bottom")
		(35 "F.Fab" user "Ref Des/Assembly Top")
		(33 "B.Fab" user "Ref Des/Assembly Bottom")
	)
	(footprint ""
		(layer "F.Cu")
		(at 270.000222 -76.550012 180)
		(property "Reference" "U5D1"
			(at 19.124422 31.601918 0)
			(unlocked yes)
			(layer "F.SilkS")
			(effects
				(font
					(size 0.7874 0.5842)
					(thickness 0.1524)
				)
			)
		)
		(property "Value" ""
			(at 0 0 180)
			(layer "F.Fab")
			(effects
				(font
					(size 1.27 1.27)
				)
			)
		)
		(duplicate_pad_numbers_are_jumpers no)
		(pad "EC50" smd circle
			(at 6.344412 23.617174)
			(size 0.4318 0.4318)
			(layers "F.Cu" "F.Mask" "F.Paste")
			(net "PVDDQ_DEF")
		)
		(pad "EC52" smd circle
			(at 8.061452 23.617174)
			(size 0.4318 0.4318)
			(layers "F.Cu" "F.Mask" "F.Paste")
			(net "PVDDQ_DEF")
		)
		(pad "EC54" smd circle
			(at 9.778492 23.617174)
			(size 0.4318 0.4318)
			(layers "F.Cu" "F.Mask" "F.Paste")
			(net "PVDDQ_DEF")
		)
		(pad "EC56" smd circle
			(at 11.495532 23.617174)
			(size 0.4318 0.4318)
			(layers "F.Cu" "F.Mask" "F.Paste")
			(net "PVDDQ_DEF")
		)
		(pad "EC58" smd circle
			(at 13.212572 23.617174)
			(size 0.4318 0.4318)
			(layers "F.Cu" "F.Mask" "F.Paste")
			(net "PVDDQ_DEF")
		)
		(pad "EC60" smd circle
			(at 14.929612 23.617174)
			(size 0.4318 0.4318)
			(layers "F.Cu" "F.Mask" "F.Paste")
			(net "PVDDQ_DEF")
		)
		(pad "EC62" smd circle
			(at 16.646398 23.617174)
			(size 0.4318 0.4318)
			(layers "F.Cu" "F.Mask" "F.Paste")
			(net "PVDDQ_DEF")
		)
		(pad "EC70" smd circle
			(at 23.514558 23.617174)
			(size 0.4318 0.4318)
			(layers "F.Cu" "F.Mask" "F.Paste")
			(net "GND")
		)
		(pad "EC72" smd circle
			(at 25.231598 23.617174)
			(size 0.4318 0.4318)
			(layers "F.Cu" "F.Mask" "F.Paste")
			(net "GND")
		)
		(pad "EC74" smd circle
			(at 26.948384 23.617174)
			(size 0.4318 0.4318)
			(layers "F.Cu" "F.Mask" "F.Paste")
			(net "GND")
		)
		(pad "EC76" smd circle
			(at 28.665424 23.617174)
			(size 0.4318 0.4318)
			(layers "F.Cu" "F.Mask" "F.Paste")
			(net "GND")
		)
		(pad "EC78" smd circle
			(at 30.382464 23.617174)
			(size 0.4318 0.4318)
			(layers "F.Cu" "F.Mask" "F.Paste")
			(net "M_E_DQ<23>")
		)
		(pad "EC80" smd circle
			(at 32.099504 23.617174)
			(size 0.4318 0.4318)
			(layers "F.Cu" "F.Mask" "F.Paste")
			(net "M_E_DQ<17>")
		)
		(pad "EC82" smd custom
			(at 33.816544 23.617174 225)
			(size 0.10795 0.10795)
			(layers "F.Cu" "F.Mask" "F.Paste")
			(net "GND")
			(options
				(clearance outline)
				(anchor circle)
			)
			(primitives
				(gr_poly
					(pts
						(arc
							(start 0.2159 -0.0381)
							(mid 0 -0.254)
							(end -0.2159 -0.0381)
						)
						(arc
							(start -0.2159 0.0381)
							(mid 0 0.254)
							(end 0.2159 0.0381)
						)
					)
					(width 0)
					(fill yes)
				)
			)
		)
		(pad "EC84" smd custom
			(at 35.533584 23.617174 270)
			(size 0.10795 0.10795)
			(layers "F.Cu" "F.Mask" "F.Paste")
			(net "TP_CPU0_RSVD_12")
			(options
				(clearance outline)
				(anchor circle)
			)
			(primitives
				(gr_poly
					(pts
						(arc
							(start 0.2159 -0.0381)
							(mid 0 -0.254)
							(end -0.2159 -0.0381)
						)
						(arc
							(start -0.2159 0.0381)
							(mid 0 0.254)
							(end 0.2159 0.0381)
						)
					)
					(width 0)
					(fill yes)
				)
			)
		)
		(pad "ED5" smd custom
			(at -33.816544 25.912572 135)
			(size 0.10795 0.10795)
			(layers "F.Cu" "F.Mask" "F.Paste")
			(net "TP_CPU0_RSVD_10")
			(options
				(clearance outline)
				(anchor circle)
			)
			(primitives
				(gr_poly
					(pts
						(arc
							(start 0.2159 -0.0381)
							(mid 0 -0.254)
							(end -0.2159 -0.0381)
						)
						(arc
							(start -0.2159 0.0381)
							(mid 0 0.254)
							(end 0.2159 0.0381)
						)
					)
					(width 0)
					(fill yes)
				)
			)
		)
		(pad "ED7" smd custom
			(at -32.099504 25.912572 135)
			(size 0.10795 0.10795)
			(layers "F.Cu" "F.Mask" "F.Paste")
			(net "GND")
			(options
				(clearance outline)
				(anchor circle)
			)
			(primitives
				(gr_poly
					(pts
						(arc
							(start 0.2159 -0.0381)
							(mid 0 -0.254)
							(end -0.2159 -0.0381)
						)
						(arc
							(start -0.2159 0.0381)
							(mid 0 0.254)
							(end 0.2159 0.0381)
						)
					)
					(width 0)
					(fill yes)
				)
			)
		)
		(pad "ED9" smd circle
			(at -30.382464 25.912572)
			(size 0.4318 0.4318)
			(layers "F.Cu" "F.Mask" "F.Paste")
			(net "P3E_CPU0_PE1_PCH_TXN<15>")
		)
		(pad "ED11" smd circle
			(at -28.665424 25.912572)
			(size 0.4318 0.4318)
			(layers "F.Cu" "F.Mask" "F.Paste")
			(net "GND")
		)
		(pad "ED13" smd circle
			(at -26.948384 25.912572)
			(size 0.4318 0.4318)
			(layers "F.Cu" "F.Mask" "F.Paste")
			(net "P3E_CPU0_PE3_OCP_TXP<1>")
		)
		(pad "ED15" smd circle
			(at -25.231598 25.912572)
			(size 0.4318 0.4318)
			(layers "F.Cu" "F.Mask" "F.Paste")
			(net "GND")
		)
		(pad "ED23" smd custom
			(at -18.363438 25.912572 120)
			(size 0.10795 0.10795)
			(layers "F.Cu" "F.Mask" "F.Paste")
			(net "GND")
			(options
				(clearance outline)
				(anchor circle)
			)
			(primitives
				(gr_poly
					(pts
						(arc
							(start 0.2159 -0.0381)
							(mid 0 -0.254)
							(end -0.2159 -0.0381)
						)
						(arc
							(start -0.2159 0.0381)
							(mid 0 0.254)
							(end 0.2159 0.0381)
						)
					)
					(width 0)
					(fill yes)
				)
			)
		)
		(pad "ED25" smd circle
			(at -16.646398 25.912572)
			(size 0.4318 0.4318)
			(layers "F.Cu" "F.Mask" "F.Paste")
			(net "M_E_DQ<55>")
		)
		(pad "ED27" smd circle
			(at -14.929612 25.912572)
			(size 0.4318 0.4318)
			(layers "F.Cu" "F.Mask" "F.Paste")
			(net "M_E_DQ<49>")
		)
		(pad "ED29" smd circle
			(at -13.212572 25.912572)
			(size 0.4318 0.4318)
			(layers "F.Cu" "F.Mask" "F.Paste")
			(net "GND")
		)
		(pad "ED31" smd circle
			(at -11.495532 25.912572)
			(size 0.4318 0.4318)
			(layers "F.Cu" "F.Mask" "F.Paste")
			(net "M_E_DQ<47>")
		)
		(pad "ED33" smd circle
			(at -9.778492 25.912572)
			(size 0.4318 0.4318)
			(layers "F.Cu" "F.Mask" "F.Paste")
			(net "M_E_DQ<41>")
		)
		(pad "ED35" smd circle
			(at -8.061452 25.912572)
			(size 0.4318 0.4318)
			(layers "F.Cu" "F.Mask" "F.Paste")
			(net "GND")
		)
		(pad "ED37" smd circle
			(at -6.344412 25.912572)
			(size 0.4318 0.4318)
			(layers "F.Cu" "F.Mask" "F.Paste")
			(net "M_D_DQ<39>")
		)
		(pad "ED39" smd circle
			(at -4.627626 25.912572)
			(size 0.4318 0.4318)
			(layers "F.Cu" "F.Mask" "F.Paste")
			(net "M_D_DQ<33>")
		)
		(pad "ED41" smd custom
			(at -2.910586 25.912572 225)
			(size 0.10795 0.10795)
			(layers "F.Cu" "F.Mask" "F.Paste")
			(net "GND")
			(options
				(clearance outline)
				(anchor circle)
			)
			(primitives
				(gr_poly
					(pts
						(arc
							(start 0.2159 -0.0381)
							(mid 0 -0.254)
							(end -0.2159 -0.0381)
						)
						(arc
							(start -0.2159 0.0381)
							(mid 0 0.254)
							(end 0.2159 0.0381)
						)
					)
					(width 0)
					(fill yes)
				)
			)
		)
		(pad "ED45" smd circle
			(at 2.052066 24.112474)
			(size 0.4318 0.4318)
			(layers "F.Cu" "F.Mask" "F.Paste")
			(net "TP_CPU0_RSVD_11")
		)
		(pad "ED47" smd circle
			(at 3.769106 24.112474)
			(size 0.4318 0.4318)
			(layers "F.Cu" "F.Mask" "F.Paste")
			(net "M_D_CS_N<2>")
		)
		(pad "ED49" smd circle
			(at 5.485892 24.112474)
			(size 0.4318 0.4318)
			(layers "F.Cu" "F.Mask" "F.Paste")
			(net "M_D_CS_N<1>")
		)
		(pad "ED51" smd circle
			(at 7.202932 24.112474)
			(size 0.4318 0.4318)
			(layers "F.Cu" "F.Mask" "F.Paste")
			(net "M_D_MA<14>")
		)
		(pad "ED53" smd circle
			(at 8.919972 24.112474)
			(size 0.4318 0.4318)
			(layers "F.Cu" "F.Mask" "F.Paste")
			(net "M_D_PAR")
		)
		(pad "ED55" smd circle
			(at 10.637012 24.112474)
			(size 0.4318 0.4318)
			(layers "F.Cu" "F.Mask" "F.Paste")
			(net "M_D_CLK_DN<0>")
		)
		(pad "ED57" smd circle
			(at 12.354052 24.112474)
			(size 0.4318 0.4318)
			(layers "F.Cu" "F.Mask" "F.Paste")
			(net "M_D_MA<1>")
		)
		(pad "ED59" smd circle
			(at 14.071092 24.112474)
			(size 0.4318 0.4318)
			(layers "F.Cu" "F.Mask" "F.Paste")
			(net "M_D_MA<4>")
		)
		(pad "ED61" smd circle
			(at 15.787878 24.112474)
			(size 0.4318 0.4318)
			(layers "F.Cu" "F.Mask" "F.Paste")
			(net "M_D_BG<0>")
		)
		(pad "ED63" smd custom
			(at 17.504918 24.112474 180)
			(size 0.10795 0.10795)
			(layers "F.Cu" "F.Mask" "F.Paste")
			(net "M_D_ALERT_N")
			(options
				(clearance outline)
				(anchor circle)
			)
			(primitives
				(gr_poly
					(pts
						(arc
							(start 0.2159 -0.0381)
							(mid 0 -0.254)
							(end -0.2159 -0.0381)
						)
						(arc
							(start -0.2159 0.0381)
							(mid 0 0.254)
							(end 0.2159 0.0381)
						)
					)
					(width 0)
					(fill yes)
				)
			)
		)
		(pad "ED69" smd custom
			(at 22.656038 24.112474 180)
			(size 0.10795 0.10795)
			(layers "F.Cu" "F.Mask" "F.Paste")
			(net "GND")
			(options
				(clearance outline)
				(anchor circle)
			)
			(primitives
				(gr_poly
					(pts
						(arc
							(start 0.2159 -0.0381)
							(mid 0 -0.254)
							(end -0.2159 -0.0381)
						)
						(arc
							(start -0.2159 0.0381)
							(mid 0 0.254)
							(end 0.2159 0.0381)
						)
					)
					(width 0)
					(fill yes)
				)
			)
		)
		(pad "ED71" smd circle
			(at 24.373078 24.112474)
			(size 0.4318 0.4318)
			(layers "F.Cu" "F.Mask" "F.Paste")
			(net "M_E_DQ<27>")
		)
		(pad "ED73" smd circle
			(at 26.090118 24.112474)
			(size 0.4318 0.4318)
			(layers "F.Cu" "F.Mask" "F.Paste")
			(net "M_E_DQS_DP<3>")
		)
		(pad "ED75" smd circle
			(at 27.806904 24.112474)
			(size 0.4318 0.4318)
			(layers "F.Cu" "F.Mask" "F.Paste")
			(net "M_E_DQ<24>")
		)
		(pad "ED77" smd circle
			(at 29.523944 24.112474)
			(size 0.4318 0.4318)
			(layers "F.Cu" "F.Mask" "F.Paste")
			(net "GND")
		)
		(pad "ED79" smd circle
			(at 31.240984 24.112474)
			(size 0.4318 0.4318)
			(layers "F.Cu" "F.Mask" "F.Paste")
			(net "M_E_DQS_DN<2>")
		)
		(pad "ED81" smd custom
			(at 32.958024 24.112474 225)
			(size 0.10795 0.10795)
			(layers "F.Cu" "F.Mask" "F.Paste")
			(net "GND")
			(options
				(clearance outline)
				(anchor circle)
			)
			(primitives
				(gr_poly
					(pts
						(arc
							(start 0.2159 -0.0381)
							(mid 0 -0.254)
							(end -0.2159 -0.0381)
						)
						(arc
							(start -0.2159 0.0381)
							(mid 0 0.254)
							(end 0.2159 0.0381)
						)
					)
					(width 0)
					(fill yes)
				)
			)
		)
		(pad "ED83" smd custom
			(at 34.675064 24.112474 270)
			(size 0.10795 0.10795)
			(layers "F.Cu" "F.Mask" "F.Paste")
			(net "TP_CPU0_RSVD_9")
			(options
				(clearance outline)
				(anchor circle)
			)
			(primitives
				(gr_poly
					(pts
						(arc
							(start 0.2159 -0.0381)
							(mid 0 -0.254)
							(end -0.2159 -0.0381)
						)
						(arc
							(start -0.2159 0.0381)
							(mid 0 0.254)
							(end 0.2159 0.0381)
						)
					)
					(width 0)
					(fill yes)
				)
			)
		)
		(pad "EE6" smd custom
			(at -32.958024 26.408126 135)
			(size 0.10795 0.10795)
			(layers "F.Cu" "F.Mask" "F.Paste")
			(net "TP_CPU0_RSVD_6")
			(options
				(clearance outline)
				(anchor circle)
			)
			(primitives
				(gr_poly
					(pts
						(arc
							(start 0.2159 -0.0381)
							(mid 0 -0.254)
							(end -0.2159 -0.0381)
						)
						(arc
							(start -0.2159 0.0381)
							(mid 0 0.254)
							(end 0.2159 0.0381)
						)
					)
					(width 0)
					(fill yes)
				)
			)
		)
		(pad "EE8" smd custom
			(at -31.240984 26.408126 135)
			(size 0.10795 0.10795)
			(layers "F.Cu" "F.Mask" "F.Paste")
			(net "GND")
			(options
				(clearance outline)
				(anchor circle)
			)
			(primitives
				(gr_poly
					(pts
						(arc
							(start 0.2159 -0.0381)
							(mid 0 -0.254)
							(end -0.2159 -0.0381)
						)
						(arc
							(start -0.2159 0.0381)
							(mid 0 0.254)
							(end 0.2159 0.0381)
						)
					)
					(width 0)
					(fill yes)
				)
			)
		)
		(pad "EE10" smd custom
			(at -29.523944 26.408126 180)
			(size 0.10795 0.10795)
			(layers "F.Cu" "F.Mask" "F.Paste")
			(net "PVCCIO_CPU0")
			(options
				(clearance outline)
				(anchor circle)
			)
			(primitives
				(gr_poly
					(pts
						(arc
							(start 0.2159 -0.0381)
							(mid 0 -0.254)
							(end -0.2159 -0.0381)
						)
						(arc
							(start -0.2159 0.0381)
							(mid 0 0.254)
							(end 0.2159 0.0381)
						)
					)
					(width 0)
					(fill yes)
				)
			)
		)
		(pad "EE12" smd custom
			(at -27.806904 26.408126 180)
			(size 0.10795 0.10795)
			(layers "F.Cu" "F.Mask" "F.Paste")
			(net "P3E_CPU0_PE3_OCP_TXN<1>")
			(options
				(clearance outline)
				(anchor circle)
			)
			(primitives
				(gr_poly
					(pts
						(arc
							(start 0.2159 -0.0381)
							(mid 0 -0.254)
							(end -0.2159 -0.0381)
						)
						(arc
							(start -0.2159 0.0381)
							(mid 0 0.254)
							(end 0.2159 0.0381)
						)
					)
					(width 0)
					(fill yes)
				)
			)
		)
		(pad "EE14" smd custom
			(at -26.090118 26.408126 180)
			(size 0.10795 0.10795)
			(layers "F.Cu" "F.Mask" "F.Paste")
			(net "P3E_CPU0_PE3_OCP_TXN<0>")
			(options
				(clearance outline)
				(anchor circle)
			)
			(primitives
				(gr_poly
					(pts
						(arc
							(start 0.2159 -0.0381)
							(mid 0 -0.254)
							(end -0.2159 -0.0381)
						)
						(arc
							(start -0.2159 0.0381)
							(mid 0 0.254)
							(end 0.2159 0.0381)
						)
					)
					(width 0)
					(fill yes)
				)
			)
		)
		(pad "EE16" smd custom
			(at -24.373078 26.408126 180)
			(size 0.10795 0.10795)
			(layers "F.Cu" "F.Mask" "F.Paste")
			(net "TP_CPU0_RSVD_8")
			(options
				(clearance outline)
				(anchor circle)
			)
			(primitives
				(gr_poly
					(pts
						(arc
							(start 0.2159 -0.0381)
							(mid 0 -0.254)
							(end -0.2159 -0.0381)
						)
						(arc
							(start -0.2159 0.0381)
							(mid 0 0.254)
							(end 0.2159 0.0381)
						)
					)
					(width 0)
					(fill yes)
				)
			)
		)
		(pad "EE24" smd custom
			(at -17.504918 26.408126 120)
			(size 0.10795 0.10795)
			(layers "F.Cu" "F.Mask" "F.Paste")
			(net "GND")
			(options
				(clearance outline)
				(anchor circle)
			)
			(primitives
				(gr_poly
					(pts
						(arc
							(start 0.2159 -0.0381)
							(mid 0 -0.254)
							(end -0.2159 -0.0381)
						)
						(arc
							(start -0.2159 0.0381)
							(mid 0 0.254)
							(end 0.2159 0.0381)
						)
					)
					(width 0)
					(fill yes)
				)
			)
		)
		(pad "EE26" smd custom
			(at -15.787878 26.408126 180)
			(size 0.10795 0.10795)
			(layers "F.Cu" "F.Mask" "F.Paste")
			(net "M_E_DQS_DN<6>")
			(options
				(clearance outline)
				(anchor circle)
			)
			(primitives
				(gr_poly
					(pts
						(arc
							(start 0.2159 -0.0381)
							(mid 0 -0.254)
							(end -0.2159 -0.0381)
						)
						(arc
							(start -0.2159 0.0381)
							(mid 0 0.254)
							(end 0.2159 0.0381)
						)
					)
					(width 0)
					(fill yes)
				)
			)
		)
		(pad "EE28" smd custom
			(at -14.071092 26.408126 180)
			(size 0.10795 0.10795)
			(layers "F.Cu" "F.Mask" "F.Paste")
			(net "GND")
			(options
				(clearance outline)
				(anchor circle)
			)
			(primitives
				(gr_poly
					(pts
						(arc
							(start 0.2159 -0.0381)
							(mid 0 -0.254)
							(end -0.2159 -0.0381)
						)
						(arc
							(start -0.2159 0.0381)
							(mid 0 0.254)
							(end 0.2159 0.0381)
						)
					)
					(width 0)
					(fill yes)
				)
			)
		)
		(pad "EE30" smd custom
			(at -12.354052 26.408126 180)
			(size 0.10795 0.10795)
			(layers "F.Cu" "F.Mask" "F.Paste")
			(net "GND")
			(options
				(clearance outline)
				(anchor circle)
			)
			(primitives
				(gr_poly
					(pts
						(arc
							(start 0.2159 -0.0381)
							(mid 0 -0.254)
							(end -0.2159 -0.0381)
						)
						(arc
							(start -0.2159 0.0381)
							(mid 0 0.254)
							(end 0.2159 0.0381)
						)
					)
					(width 0)
					(fill yes)
				)
			)
		)
		(pad "EE32" smd custom
			(at -10.637012 26.408126 180)
			(size 0.10795 0.10795)
			(layers "F.Cu" "F.Mask" "F.Paste")
			(net "M_E_DQS_DN<5>")
			(options
				(clearance outline)
				(anchor circle)
			)
			(primitives
				(gr_poly
					(pts
						(arc
							(start 0.2159 -0.0381)
							(mid 0 -0.254)
							(end -0.2159 -0.0381)
						)
						(arc
							(start -0.2159 0.0381)
							(mid 0 0.254)
							(end 0.2159 0.0381)
						)
					)
					(width 0)
					(fill yes)
				)
			)
		)
		(pad "EE34" smd custom
			(at -8.919972 26.408126 180)
			(size 0.10795 0.10795)
			(layers "F.Cu" "F.Mask" "F.Paste")
			(net "GND")
			(options
				(clearance outline)
				(anchor circle)
			)
			(primitives
				(gr_poly
					(pts
						(arc
							(start 0.2159 -0.0381)
							(mid 0 -0.254)
							(end -0.2159 -0.0381)
						)
						(arc
							(start -0.2159 0.0381)
							(mid 0 0.254)
							(end 0.2159 0.0381)
						)
					)
					(width 0)
					(fill yes)
				)
			)
		)
		(pad "EE36" smd custom
			(at -7.202932 26.408126 180)
			(size 0.10795 0.10795)
			(layers "F.Cu" "F.Mask" "F.Paste")
			(net "GND")
			(options
				(clearance outline)
				(anchor circle)
			)
			(primitives
				(gr_poly
					(pts
						(arc
							(start 0.2159 -0.0381)
							(mid 0 -0.254)
							(end -0.2159 -0.0381)
						)
						(arc
							(start -0.2159 0.0381)
							(mid 0 0.254)
							(end 0.2159 0.0381)
						)
					)
					(width 0)
					(fill yes)
				)
			)
		)
		(pad "EE38" smd custom
			(at -5.485892 26.408126 180)
			(size 0.10795 0.10795)
			(layers "F.Cu" "F.Mask" "F.Paste")
			(net "M_D_DQS_DN<4>")
			(options
				(clearance outline)
				(anchor circle)
			)
			(primitives
				(gr_poly
					(pts
						(arc
							(start 0.2159 -0.0381)
							(mid 0 -0.254)
							(end -0.2159 -0.0381)
						)
						(arc
							(start -0.2159 0.0381)
							(mid 0 0.254)
							(end 0.2159 0.0381)
						)
					)
					(width 0)
					(fill yes)
				)
			)
		)
		(pad "EE40" smd custom
			(at -3.769106 26.408126 225)
			(size 0.10795 0.10795)
			(layers "F.Cu" "F.Mask" "F.Paste")
			(net "GND")
			(options
				(clearance outline)
				(anchor circle)
			)
			(primitives
				(gr_poly
					(pts
						(arc
							(start 0.2159 -0.0381)
							(mid 0 -0.254)
							(end -0.2159 -0.0381)
						)
						(arc
							(start -0.2159 0.0381)
							(mid 0 0.254)
							(end 0.2159 0.0381)
						)
					)
					(width 0)
					(fill yes)
				)
			)
		)
		(pad "EE44" smd custom
			(at 1.193546 24.608028 135)
			(size 0.10795 0.10795)
			(layers "F.Cu" "F.Mask" "F.Paste")
			(net "PVDDQ_DEF")
			(options
				(clearance outline)
				(anchor circle)
			)
			(primitives
				(gr_poly
					(pts
						(arc
							(start 0.2159 -0.0381)
							(mid 0 -0.254)
							(end -0.2159 -0.0381)
						)
						(arc
							(start -0.2159 0.0381)
							(mid 0 0.254)
							(end 0.2159 0.0381)
						)
					)
					(width 0)
					(fill yes)
				)
			)
		)
		(pad "EE46" smd circle
			(at 2.910586 24.608028)
			(size 0.4318 0.4318)
			(layers "F.Cu" "F.Mask" "F.Paste")
			(net "TP_CPU0_RSVD_7")
		)
	)
)
